(kicad_pcb
	(version 20260206)
	(generator "pcbnew")
	(generator_version "10.0")
	(general
		(thickness 1.6)
		(legacy_teardrops no)
	)
	(paper "A4")
	(title_block
		(title "Wiwynn_Tioga_Pass_MB.brd")
		(comment 1 "Tioga Pass / footprints 2007-2007 of 4770")
	)
	(layers
		(0 "F.Cu" signal "TOP")
		(4 "In1.Cu" signal "L2GND")
		(6 "In2.Cu" signal "L3")
		(8 "In3.Cu" signal "L4GND")
		(10 "In4.Cu" signal "L5")
		(12 "In5.Cu" signal "L6GND")
		(14 "In6.Cu" signal "L7VCC")
		(16 "In7.Cu" signal "L8VCC")
		(18 "In8.Cu" signal "L9GND")
		(20 "In9.Cu" signal "L10")
		(22 "In10.Cu" signal "L11GND")
		(24 "In11.Cu" signal "L12")
		(26 "In12.Cu" signal "L13GND")
		(2 "B.Cu" signal "BOTTOM")
		(9 "F.Adhes" user "F.Adhesive")
		(11 "B.Adhes" user "B.Adhesive")
		(13 "F.Paste" user "Package Geometry/Pastemask Top")
		(15 "B.Paste" user "Package Geometry/Pastemask Bottom")
		(5 "F.SilkS" user "Ref Des/Silkscreen Top")
		(7 "B.SilkS" user "Ref Des/Silkscreen Bottom")
		(1 "F.Mask" user "Board Geometry/Soldermask Top")
		(3 "B.Mask" user "Board Geometry/Soldermask Bottom")
		(17 "Dwgs.User" user "User.Drawings")
		(19 "Cmts.User" user "User.Comments")
		(21 "Eco1.User" user "User.Eco1")
		(23 "Eco2.User" user "User.Eco2")
		(25 "Edge.Cuts" user "Board Geometry/Outline")
		(27 "Margin" user)
		(31 "F.CrtYd" user "Package Geometry/Place Bound Top")
		(29 "B.CrtYd" user "Package Geometry/Place Bound Bottom")
		(35 "F.Fab" user "Ref Des/Assembly Top")
		(33 "B.Fab" user "Ref Des/Assembly Bottom")
	)
	(footprint ""
		(layer "F.Cu")
		(at 173.78172 -147.95246 90)
		(property "Reference" "C4A7"
			(at 0 0 90)
			(layer "F.SilkS")
			(hide yes)
			(effects
				(font
					(size 1.27 1.27)
				)
			)
		)
		(property "Value" ""
			(at 0 0 90)
			(layer "F.Fab")
			(effects
				(font
					(size 1.27 1.27)
				)
			)
		)
		(duplicate_pad_numbers_are_jumpers no)
		(fp_poly
			(pts
				(xy -0.4953 -0.2032) (xy 0.4953 -0.2032) (xy 0.4953 1.6002) (xy -0.4953 1.6002)
			)
			(stroke
				(width 0)
				(type default)
			)
			(fill no)
			(layer "F.CrtYd")
		)
		(fp_line
			(start 0.4953 -0.2032)
			(end 0.4953 1.6002)
			(stroke
				(width 0.1)
				(type default)
			)
			(layer "F.Fab")
		)
		(fp_line
			(start -0.4953 -0.2032)
			(end 0.4953 -0.2032)
			(stroke
				(width 0.1)
				(type default)
			)
			(layer "F.Fab")
		)
		(fp_line
			(start 0.4953 1.6002)
			(end -0.4953 1.6002)
			(stroke
				(width 0.1)
				(type default)
			)
			(layer "F.Fab")
		)
		(fp_line
			(start -0.4953 1.6002)
			(end -0.4953 -0.2032)
			(stroke
				(width 0.1)
				(type default)
			)
			(layer "F.Fab")
		)
		(pad "1" smd rect
			(at 0 0 90)
			(size 0.762 0.889)
			(layers "F.Cu" "F.Mask" "F.Paste")
			(net "VSENSE_PVDDQ_KLM_VTT")
		)
		(pad "2" smd rect
			(at 0 1.397 90)
			(size 0.762 0.889)
			(layers "F.Cu" "F.Mask" "F.Paste")
			(net "GND")
		)
		(zone
			(layer "F.Cu")
			(hatch none 0.5)
			(connect_pads
				(clearance 0)
			)
			(min_thickness 0.25)
			(keepout
				(tracks not_allowed)
				(vias allowed)
				(pads allowed)
				(copperpour not_allowed)
				(footprints allowed)
			)
			(placement
				(enabled no)
				(sheetname "")
			)
			(fill
				(thermal_gap 0.5)
				(thermal_bridge_width 0.5)
				(island_removal_mode 0)
			)
			(polygon
				(pts
					(xy 174.22622 -147.57146) (xy 174.22622 -148.33346) (xy 174.73422 -148.33346) (xy 174.73422 -147.57146)
				)
			)
		)
	)
)
